(kicad_pcb
	(version 20260206)
	(generator "pcbnew")
	(generator_version "10.0")
	(general
		(thickness 1.6)
		(legacy_teardrops no)
	)
	(paper "A4")
	(title_block
		(title "Wiwynn_Tioga_Pass_MB.brd")
		(comment 1 "Tioga Pass / footprints 2036-2042 of 4770")
	)
	(layers
		(0 "F.Cu" signal "TOP")
		(4 "In1.Cu" signal "L2GND")
		(6 "In2.Cu" signal "L3")
		(8 "In3.Cu" signal "L4GND")
		(10 "In4.Cu" signal "L5")
		(12 "In5.Cu" signal "L6GND")
		(14 "In6.Cu" signal "L7VCC")
		(16 "In7.Cu" signal "L8VCC")
		(18 "In8.Cu" signal "L9GND")
		(20 "In9.Cu" signal "L10")
		(22 "In10.Cu" signal "L11GND")
		(24 "In11.Cu" signal "L12")
		(26 "In12.Cu" signal "L13GND")
		(2 "B.Cu" signal "BOTTOM")
		(9 "F.Adhes" user "F.Adhesive")
		(11 "B.Adhes" user "B.Adhesive")
		(13 "F.Paste" user "Package Geometry/Pastemask Top")
		(15 "B.Paste" user "Package Geometry/Pastemask Bottom")
		(5 "F.SilkS" user "Ref Des/Silkscreen Top")
		(7 "B.SilkS" user "Ref Des/Silkscreen Bottom")
		(1 "F.Mask" user "Board Geometry/Soldermask Top")
		(3 "B.Mask" user "Board Geometry/Soldermask Bottom")
		(17 "Dwgs.User" user "User.Drawings")
		(19 "Cmts.User" user "User.Comments")
		(21 "Eco1.User" user "User.Eco1")
		(23 "Eco2.User" user "User.Eco2")
		(25 "Edge.Cuts" user "Board Geometry/Outline")
		(27 "Margin" user)
		(31 "F.CrtYd" user "Package Geometry/Place Bound Top")
		(29 "B.CrtYd" user "Package Geometry/Place Bound Bottom")
		(35 "F.Fab" user "Ref Des/Assembly Top")
		(33 "B.Fab" user "Ref Des/Assembly Bottom")
	)
	(footprint ""
		(layer "F.Cu")
		(at 116.3066 -72.263 90)
		(property "Reference" "R3D17"
			(at 0 0 90)
			(layer "F.SilkS")
			(hide yes)
			(effects
				(font
					(size 1.27 1.27)
				)
			)
		)
		(property "Value" ""
			(at 0 0 90)
			(layer "F.Fab")
			(effects
				(font
					(size 1.27 1.27)
				)
			)
		)
		(duplicate_pad_numbers_are_jumpers no)
		(fp_poly
			(pts
				(xy -0.2794 -0.1016) (xy 0.2794 -0.1016) (xy 0.2794 0.9906) (xy -0.2794 0.9906)
			)
			(stroke
				(width 0)
				(type default)
			)
			(fill no)
			(layer "F.CrtYd")
		)
		(fp_line
			(start 0.2794 -0.1016)
			(end -0.2794 -0.1016)
			(stroke
				(width 0.1)
				(type default)
			)
			(layer "F.Fab")
		)
		(fp_line
			(start -0.2794 -0.1016)
			(end -0.2794 0.9906)
			(stroke
				(width 0.1)
				(type default)
			)
			(layer "F.Fab")
		)
		(fp_line
			(start 0.2794 0.9906)
			(end 0.2794 -0.1016)
			(stroke
				(width 0.1)
				(type default)
			)
			(layer "F.Fab")
		)
		(fp_line
			(start -0.2794 0.9906)
			(end 0.2794 0.9906)
			(stroke
				(width 0.1)
				(type default)
			)
			(layer "F.Fab")
		)
		(pad "1" smd rect
			(at 0 0 90)
			(size 0.508 0.508)
			(layers "F.Cu" "F.Mask" "F.Paste")
			(net "PVCCIO_CPU1")
		)
		(pad "2" smd rect
			(at 0 0.889 90)
			(size 0.508 0.508)
			(layers "F.Cu" "F.Mask" "F.Paste")
			(net "PU_CPU1_SOCKET_ID_1")
		)
		(zone
			(layer "F.Cu")
			(hatch none 0.5)
			(connect_pads
				(clearance 0)
			)
			(min_thickness 0.25)
			(keepout
				(tracks allowed)
				(vias not_allowed)
				(pads allowed)
				(copperpour not_allowed)
				(footprints allowed)
			)
			(placement
				(enabled no)
				(sheetname "")
			)
			(fill
				(thermal_gap 0.5)
				(thermal_bridge_width 0.5)
				(island_removal_mode 0)
			)
			(polygon
				(pts
					(xy 116.5606 -72.009) (xy 116.5606 -72.517) (xy 116.9416 -72.517) (xy 116.9416 -72.009)
				)
			)
		)
		(zone
			(layer "F.Cu")
			(hatch none 0.5)
			(connect_pads
				(clearance 0)
			)
			(min_thickness 0.25)
			(keepout
				(tracks not_allowed)
				(vias allowed)
				(pads allowed)
				(copperpour not_allowed)
				(footprints allowed)
			)
			(placement
				(enabled no)
				(sheetname "")
			)
			(fill
				(thermal_gap 0.5)
				(thermal_bridge_width 0.5)
				(island_removal_mode 0)
			)
			(polygon
				(pts
					(xy 116.9416 -72.009) (xy 116.9416 -72.517) (xy 116.5606 -72.517) (xy 116.5606 -72.009)
				)
			)
		)
	)
	(footprint ""
		(layer "F.Cu")
		(at 367.966244 -10.916158)
		(property "Reference" "C7G10"
			(at 0 0 0)
			(layer "F.SilkS")
			(hide yes)
			(effects
				(font
					(size 1.27 1.27)
				)
			)
		)
		(property "Value" ""
			(at 0 0 0)
			(layer "F.Fab")
			(effects
				(font
					(size 1.27 1.27)
				)
			)
		)
		(duplicate_pad_numbers_are_jumpers no)
		(fp_rect
			(start -0.3048 0.9906)
			(end 0.3048 -0.1016)
			(stroke
				(width 0)
				(type default)
			)
			(fill no)
			(layer "F.CrtYd")
		)
		(fp_line
			(start -0.3048 -0.1016)
			(end -0.3048 0.9906)
			(stroke
				(width 0.1)
				(type default)
			)
			(layer "F.Fab")
		)
		(fp_line
			(start -0.3048 0.9906)
			(end 0.3048 0.9906)
			(stroke
				(width 0.1)
				(type default)
			)
			(layer "F.Fab")
		)
		(fp_line
			(start 0.3048 -0.1016)
			(end -0.3048 -0.1016)
			(stroke
				(width 0.1)
				(type default)
			)
			(layer "F.Fab")
		)
		(fp_line
			(start 0.3048 0.9906)
			(end 0.3048 -0.1016)
			(stroke
				(width 0.1)
				(type default)
			)
			(layer "F.Fab")
		)
		(pad "1" smd rect
			(at 0 0)
			(size 0.508 0.508)
			(layers "F.Cu" "F.Mask" "F.Paste")
			(net "P3E_CPU0_PE2_SS_TXN<13>")
		)
		(pad "2" smd rect
			(at 0 0.889)
			(size 0.508 0.508)
			(layers "F.Cu" "F.Mask" "F.Paste")
			(net "P3E_CPU0_PE2_SS_C_TXN<13>")
		)
		(zone
			(layer "F.Cu")
			(hatch none 0.5)
			(connect_pads
				(clearance 0)
			)
			(min_thickness 0.25)
			(keepout
				(tracks not_allowed)
				(vias allowed)
				(pads allowed)
				(copperpour not_allowed)
				(footprints allowed)
			)
			(placement
				(enabled no)
				(sheetname "")
			)
			(fill
				(thermal_gap 0.5)
				(thermal_bridge_width 0.5)
				(island_removal_mode 0)
			)
			(polygon
				(pts
					(xy 367.712244 -10.281158) (xy 368.220244 -10.281158) (xy 368.220244 -10.662158) (xy 367.712244 -10.662158)
				)
			)
		)
		(zone
			(layer "F.Cu")
			(hatch none 0.5)
			(connect_pads
				(clearance 0)
			)
			(min_thickness 0.25)
			(keepout
				(tracks allowed)
				(vias not_allowed)
				(pads allowed)
				(copperpour not_allowed)
				(footprints allowed)
			)
			(placement
				(enabled no)
				(sheetname "")
			)
			(fill
				(thermal_gap 0.5)
				(thermal_bridge_width 0.5)
				(island_removal_mode 0)
			)
			(polygon
				(pts
					(xy 367.712244 -10.281158) (xy 368.220244 -10.281158) (xy 368.220244 -10.662158) (xy 367.712244 -10.662158)
				)
			)
		)
	)
	(footprint ""
		(layer "F.Cu")
		(at 420.624 -113.8555 180)
		(property "Reference" "R9W14"
			(at -0.8382 -0.67818 180)
			(unlocked yes)
			(layer "F.SilkS")
			(effects
				(font
					(size 0.4064 0.254)
					(thickness 0.1524)
				)
				(justify left)
			)
		)
		(property "Value" ""
			(at 0 0 180)
			(layer "F.Fab")
			(effects
				(font
					(size 1.27 1.27)
				)
			)
		)
		(duplicate_pad_numbers_are_jumpers no)
		(fp_poly
			(pts
				(xy -0.2794 -0.1016) (xy 0.2794 -0.1016) (xy 0.2794 0.9906) (xy -0.2794 0.9906)
			)
			(stroke
				(width 0)
				(type default)
			)
			(fill no)
			(layer "F.CrtYd")
		)
		(fp_line
			(start 0.2794 0.9906)
			(end 0.2794 -0.1016)
			(stroke
				(width 0.1)
				(type default)
			)
			(layer "F.Fab")
		)
		(fp_line
			(start 0.2794 -0.1016)
			(end -0.2794 -0.1016)
			(stroke
				(width 0.1)
				(type default)
			)
			(layer "F.Fab")
		)
		(fp_line
			(start -0.2794 0.9906)
			(end 0.2794 0.9906)
			(stroke
				(width 0.1)
				(type default)
			)
			(layer "F.Fab")
		)
		(fp_line
			(start -0.2794 -0.1016)
			(end -0.2794 0.9906)
			(stroke
				(width 0.1)
				(type default)
			)
			(layer "F.Fab")
		)
		(pad "1" smd rect
			(at 0 0 180)
			(size 0.508 0.508)
			(layers "F.Cu" "F.Mask" "F.Paste")
			(net "SMB_PEHPCPU0_STBY_LVC3_R_SCL")
		)
		(pad "2" smd rect
			(at 0 0.889 180)
			(size 0.508 0.508)
			(layers "F.Cu" "F.Mask" "F.Paste")
			(net "SMB_PEHPCPU0_STBY_LVC3_SCL")
		)
		(zone
			(layer "F.Cu")
			(hatch none 0.5)
			(connect_pads
				(clearance 0)
			)
			(min_thickness 0.25)
			(keepout
				(tracks not_allowed)
				(vias allowed)
				(pads allowed)
				(copperpour not_allowed)
				(footprints allowed)
			)
			(placement
				(enabled no)
				(sheetname "")
			)
			(fill
				(thermal_gap 0.5)
				(thermal_bridge_width 0.5)
				(island_removal_mode 0)
			)
			(polygon
				(pts
					(xy 420.878 -114.4905) (xy 420.37 -114.4905) (xy 420.37 -114.1095) (xy 420.878 -114.1095)
				)
			)
		)
		(zone
			(layer "F.Cu")
			(hatch none 0.5)
			(connect_pads
				(clearance 0)
			)
			(min_thickness 0.25)
			(keepout
				(tracks allowed)
				(vias not_allowed)
				(pads allowed)
				(copperpour not_allowed)
				(footprints allowed)
			)
			(placement
				(enabled no)
				(sheetname "")
			)
			(fill
				(thermal_gap 0.5)
				(thermal_bridge_width 0.5)
				(island_removal_mode 0)
			)
			(polygon
				(pts
					(xy 420.878 -114.1095) (xy 420.37 -114.1095) (xy 420.37 -114.4905) (xy 420.878 -114.4905)
				)
			)
		)
	)
	(footprint ""
		(layer "F.Cu")
		(at 13.462 -51.816 90)
		(property "Reference" "C1E16"
			(at 0 0 90)
			(layer "F.SilkS")
			(hide yes)
			(effects
				(font
					(size 1.27 1.27)
				)
			)
		)
		(property "Value" ""
			(at 0 0 90)
			(layer "F.Fab")
			(effects
				(font
					(size 1.27 1.27)
				)
			)
		)
		(duplicate_pad_numbers_are_jumpers no)
		(fp_rect
			(start -0.3048 -0.1016)
			(end 0.3048 0.9906)
			(stroke
				(width 0)
				(type default)
			)
			(fill no)
			(layer "F.CrtYd")
		)
		(fp_line
			(start 0.3048 -0.1016)
			(end -0.3048 -0.1016)
			(stroke
				(width 0.1)
				(type default)
			)
			(layer "F.Fab")
		)
		(fp_line
			(start -0.3048 -0.1016)
			(end -0.3048 0.9906)
			(stroke
				(width 0.1)
				(type default)
			)
			(layer "F.Fab")
		)
		(fp_line
			(start 0.3048 0.9906)
			(end 0.3048 -0.1016)
			(stroke
				(width 0.1)
				(type default)
			)
			(layer "F.Fab")
		)
		(fp_line
			(start -0.3048 0.9906)
			(end 0.3048 0.9906)
			(stroke
				(width 0.1)
				(type default)
			)
			(layer "F.Fab")
		)
		(pad "1" smd rect
			(at 0 0 90)
			(size 0.508 0.508)
			(layers "F.Cu" "F.Mask" "F.Paste")
			(net "P12V_PSU")
		)
		(pad "2" smd rect
			(at 0 0.889 90)
			(size 0.508 0.508)
			(layers "F.Cu" "F.Mask" "F.Paste")
			(net "GND")
		)
		(zone
			(layer "F.Cu")
			(hatch none 0.5)
			(connect_pads
				(clearance 0)
			)
			(min_thickness 0.25)
			(keepout
				(tracks allowed)
				(vias not_allowed)
				(pads allowed)
				(copperpour not_allowed)
				(footprints allowed)
			)
			(placement
				(enabled no)
				(sheetname "")
			)
			(fill
				(thermal_gap 0.5)
				(thermal_bridge_width 0.5)
				(island_removal_mode 0)
			)
			(polygon
				(pts
					(xy 13.716 -51.562) (xy 14.097 -51.562) (xy 14.097 -52.07) (xy 13.716 -52.07)
				)
			)
		)
		(zone
			(layer "F.Cu")
			(hatch none 0.5)
			(connect_pads
				(clearance 0)
			)
			(min_thickness 0.25)
			(keepout
				(tracks not_allowed)
				(vias allowed)
				(pads allowed)
				(copperpour not_allowed)
				(footprints allowed)
			)
			(placement
				(enabled no)
				(sheetname "")
			)
			(fill
				(thermal_gap 0.5)
				(thermal_bridge_width 0.5)
				(island_removal_mode 0)
			)
			(polygon
				(pts
					(xy 13.716 -51.562) (xy 14.097 -51.562) (xy 14.097 -52.07) (xy 13.716 -52.07)
				)
			)
		)
	)
	(footprint ""
		(layer "F.Cu")
		(at 204.8764 -61.214 -90)
		(property "Reference" "CT5"
			(at -0.8382 -0.67818 270)
			(unlocked yes)
			(layer "F.SilkS")
			(effects
				(font
					(size 0.4064 0.254)
					(thickness 0.1524)
				)
				(justify left)
			)
		)
		(property "Value" ""
			(at 0 0 270)
			(layer "F.Fab")
			(effects
				(font
					(size 1.27 1.27)
				)
			)
		)
		(duplicate_pad_numbers_are_jumpers no)
		(fp_poly
			(pts
				(xy 0.3048 -0.1016) (xy 0.3048 0.9906) (xy -0.3048 0.9906) (xy -0.3048 -0.1016)
			)
			(stroke
				(width 0)
				(type default)
			)
			(fill no)
			(layer "F.CrtYd")
		)
		(fp_line
			(start -0.3048 0.9906)
			(end 0.3048 0.9906)
			(stroke
				(width 0.1)
				(type default)
			)
			(layer "F.Fab")
		)
		(fp_line
			(start 0.3048 0.9906)
			(end 0.3048 -0.1016)
			(stroke
				(width 0.1)
				(type default)
			)
			(layer "F.Fab")
		)
		(fp_line
			(start -0.3048 -0.1016)
			(end -0.3048 0.9906)
			(stroke
				(width 0.1)
				(type default)
			)
			(layer "F.Fab")
		)
		(fp_line
			(start 0.3048 -0.1016)
			(end -0.3048 -0.1016)
			(stroke
				(width 0.1)
				(type default)
			)
			(layer "F.Fab")
		)
		(pad "1" smd rect
			(at 0 0 270)
			(size 0.508 0.508)
			(layers "F.Cu" "F.Mask" "F.Paste")
			(net "VR_PVCCIN_CPU0_PHASE2")
		)
		(pad "2" smd rect
			(at 0 0.889 270)
			(size 0.508 0.508)
			(layers "F.Cu" "F.Mask" "F.Paste")
			(net "VR_PVCCIN_CPU0_PHASE2_RC")
		)
		(zone
			(layer "F.Cu")
			(hatch none 0.5)
			(connect_pads
				(clearance 0)
			)
			(min_thickness 0.25)
			(keepout
				(tracks not_allowed)
				(vias allowed)
				(pads allowed)
				(copperpour not_allowed)
				(footprints allowed)
			)
			(placement
				(enabled no)
				(sheetname "")
			)
			(fill
				(thermal_gap 0.5)
				(thermal_bridge_width 0.5)
				(island_removal_mode 0)
			)
			(polygon
				(pts
					(xy 204.2414 -61.468) (xy 204.2414 -60.96) (xy 204.6224 -60.96) (xy 204.6224 -61.468)
				)
			)
		)
		(zone
			(layer "F.Cu")
			(hatch none 0.5)
			(connect_pads
				(clearance 0)
			)
			(min_thickness 0.25)
			(keepout
				(tracks allowed)
				(vias not_allowed)
				(pads allowed)
				(copperpour not_allowed)
				(footprints allowed)
			)
			(placement
				(enabled no)
				(sheetname "")
			)
			(fill
				(thermal_gap 0.5)
				(thermal_bridge_width 0.5)
				(island_removal_mode 0)
			)
			(polygon
				(pts
					(xy 204.6224 -61.468) (xy 204.6224 -60.96) (xy 204.2414 -60.96) (xy 204.2414 -61.468)
				)
			)
		)
	)
	(footprint ""
		(layer "F.Cu")
		(at 472.948 -144.7165)
		(property "Reference" "R9A16"
			(at 0 0 0)
			(layer "F.SilkS")
			(hide yes)
			(effects
				(font
					(size 1.27 1.27)
				)
			)
		)
		(property "Value" ""
			(at 0 0 0)
			(layer "F.Fab")
			(effects
				(font
					(size 1.27 1.27)
				)
			)
		)
		(duplicate_pad_numbers_are_jumpers no)
		(fp_poly
			(pts
				(xy -0.2794 -0.1016) (xy 0.2794 -0.1016) (xy 0.2794 0.9906) (xy -0.2794 0.9906)
			)
			(stroke
				(width 0)
				(type default)
			)
			(fill no)
			(layer "F.CrtYd")
		)
		(fp_line
			(start -0.2794 -0.1016)
			(end -0.2794 0.9906)
			(stroke
				(width 0.1)
				(type default)
			)
			(layer "F.Fab")
		)
		(fp_line
			(start -0.2794 0.9906)
			(end 0.2794 0.9906)
			(stroke
				(width 0.1)
				(type default)
			)
			(layer "F.Fab")
		)
		(fp_line
			(start 0.2794 -0.1016)
			(end -0.2794 -0.1016)
			(stroke
				(width 0.1)
				(type default)
			)
			(layer "F.Fab")
		)
		(fp_line
			(start 0.2794 0.9906)
			(end 0.2794 -0.1016)
			(stroke
				(width 0.1)
				(type default)
			)
			(layer "F.Fab")
		)
		(pad "1" smd rect
			(at 0 0)
			(size 0.508 0.508)
			(layers "F.Cu" "F.Mask" "F.Paste")
			(net "PU_KEY_CONN_PIN2_R")
		)
		(pad "2" smd rect
			(at 0 0.889)
			(size 0.508 0.508)
			(layers "F.Cu" "F.Mask" "F.Paste")
			(net "P3V3_STBY")
		)
		(zone
			(layer "F.Cu")
			(hatch none 0.5)
			(connect_pads
				(clearance 0)
			)
			(min_thickness 0.25)
			(keepout
				(tracks allowed)
				(vias not_allowed)
				(pads allowed)
				(copperpour not_allowed)
				(footprints allowed)
			)
			(placement
				(enabled no)
				(sheetname "")
			)
			(fill
				(thermal_gap 0.5)
				(thermal_bridge_width 0.5)
				(island_removal_mode 0)
			)
			(polygon
				(pts
					(xy 472.694 -144.4625) (xy 473.202 -144.4625) (xy 473.202 -144.0815) (xy 472.694 -144.0815)
				)
			)
		)
		(zone
			(layer "F.Cu")
			(hatch none 0.5)
			(connect_pads
				(clearance 0)
			)
			(min_thickness 0.25)
			(keepout
				(tracks not_allowed)
				(vias allowed)
				(pads allowed)
				(copperpour not_allowed)
				(footprints allowed)
			)
			(placement
				(enabled no)
				(sheetname "")
			)
			(fill
				(thermal_gap 0.5)
				(thermal_bridge_width 0.5)
				(island_removal_mode 0)
			)
			(polygon
				(pts
					(xy 472.694 -144.0815) (xy 473.202 -144.0815) (xy 473.202 -144.4625) (xy 472.694 -144.4625)
				)
			)
		)
	)
	(footprint ""
		(layer "F.Cu")
		(at 26.416 -64.516)
		(property "Reference" "C1E2"
			(at 0.02667 4.953 90)
			(unlocked yes)
			(layer "F.SilkS")
			(effects
				(font
					(size 0.7874 0.5842)
					(thickness 0.1524)
				)
			)
		)
		(property "Value" ""
			(at 0 0 0)
			(layer "F.Fab")
			(effects
				(font
					(size 1.27 1.27)
				)
			)
		)
		(duplicate_pad_numbers_are_jumpers no)
		(fp_line
			(start -0.9017 1.953006)
			(end -0.9017 0.823976)
			(stroke
				(width 0.1524)
				(type default)
			)
			(layer "F.SilkS")
		)
		(fp_line
			(start 0.9017 1.953768)
			(end 0.9017 0.824484)
			(stroke
				(width 0.1524)
				(type default)
			)
			(layer "F.SilkS")
		)
		(fp_poly
			(pts
				(xy -0.9017 -0.3048) (xy 0.9017 -0.3048) (xy 0.9017 3.0988) (xy -0.9017 3.0988)
			)
			(stroke
				(width 0)
				(type default)
			)
			(fill no)
			(layer "F.CrtYd")
		)
		(fp_line
			(start -0.9017 -0.3048)
			(end -0.9017 3.0988)
			(stroke
				(width 0.1)
				(type default)
			)
			(layer "F.Fab")
		)
		(fp_line
			(start -0.9017 3.0988)
			(end 0.9017 3.0988)
			(stroke
				(width 0.1)
				(type default)
			)
			(layer "F.Fab")
		)
		(fp_line
			(start 0.9017 -0.3048)
			(end -0.9017 -0.3048)
			(stroke
				(width 0.1)
				(type default)
			)
			(layer "F.Fab")
		)
		(fp_line
			(start 0.9017 3.0988)
			(end 0.9017 -0.3048)
			(stroke
				(width 0.1)
				(type default)
			)
			(layer "F.Fab")
		)
		(pad "1" smd rect
			(at 0 0)
			(size 1.524 1.016)
			(layers "F.Cu" "F.Mask" "F.Paste")
			(net "A_HSC_C")
		)
		(pad "2" smd rect
			(at 0 2.794)
			(size 1.524 1.016)
			(layers "F.Cu" "F.Mask" "F.Paste")
			(net "GND")
		)
		(zone
			(layer "F.Cu")
			(hatch none 0.5)
			(connect_pads
				(clearance 0)
			)
			(min_thickness 0.25)
			(keepout
				(tracks allowed)
				(vias not_allowed)
				(pads allowed)
				(copperpour not_allowed)
				(footprints allowed)
			)
			(placement
				(enabled no)
				(sheetname "")
			)
			(fill
				(thermal_gap 0.5)
				(thermal_bridge_width 0.5)
				(island_removal_mode 0)
			)
			(polygon
				(pts
					(xy 27.178 -64.008) (xy 27.178 -62.23) (xy 25.654 -62.23) (xy 25.654 -64.008)
				)
			)
		)
	)
)
